(kicad_pcb
	(version 20260206)
	(generator "pcbnew")
	(generator_version "10.0")
	(general
		(thickness 1.6)
		(legacy_teardrops no)
	)
	(paper "A4")
	(title_block
		(title "Wiwynn_Tioga_Pass_MB.brd")
		(comment 1 "Tioga Pass / footprint 4129 of 4770 (J6L1), pads 244-291 of 291")
	)
	(layers
		(0 "F.Cu" signal "TOP")
		(4 "In1.Cu" signal "L2GND")
		(6 "In2.Cu" signal "L3")
		(8 "In3.Cu" signal "L4GND")
		(10 "In4.Cu" signal "L5")
		(12 "In5.Cu" signal "L6GND")
		(14 "In6.Cu" signal "L7VCC")
		(16 "In7.Cu" signal "L8VCC")
		(18 "In8.Cu" signal "L9GND")
		(20 "In9.Cu" signal "L10")
		(22 "In10.Cu" signal "L11GND")
		(24 "In11.Cu" signal "L12")
		(26 "In12.Cu" signal "L13GND")
		(2 "B.Cu" signal "BOTTOM")
		(9 "F.Adhes" user "F.Adhesive")
		(11 "B.Adhes" user "B.Adhesive")
		(13 "F.Paste" user "Package Geometry/Pastemask Top")
		(15 "B.Paste" user "Package Geometry/Pastemask Bottom")
		(5 "F.SilkS" user "Ref Des/Silkscreen Top")
		(7 "B.SilkS" user "Ref Des/Silkscreen Bottom")
		(1 "F.Mask" user "Board Geometry/Soldermask Top")
		(3 "B.Mask" user "Board Geometry/Soldermask Bottom")
		(17 "Dwgs.User" user "User.Drawings")
		(19 "Cmts.User" user "User.Comments")
		(21 "Eco1.User" user "User.Eco1")
		(23 "Eco2.User" user "User.Eco2")
		(25 "Edge.Cuts" user "Board Geometry/Outline")
		(27 "Margin" user)
		(31 "F.CrtYd" user "Package Geometry/Place Bound Top")
		(29 "B.CrtYd" user "Package Geometry/Place Bound Bottom")
		(35 "F.Fab" user "Ref Des/Assembly Top")
		(33 "B.Fab" user "Ref Des/Assembly Bottom")
	)
	(footprint ""
		(layer "B.Cu")
		(at 194.700398 -152.078436 90)
		(property "Reference" "J6L1"
			(at 2.200148 37.96411 0)
			(unlocked yes)
			(layer "B.SilkS")
			(effects
				(font
					(size 0.7874 0.5842)
					(thickness 0.1524)
				)
				(justify left mirror)
			)
		)
		(property "Value" ""
			(at 0 0 90)
			(layer "B.Fab")
			(effects
				(font
					(size 1.27 1.27)
				)
				(justify mirror)
			)
		)
		(duplicate_pad_numbers_are_jumpers no)
		(pad "241" smd rect
			(at -4.59994 86.700106 270)
			(size 1.8034 0.508)
			(layers "B.Cu" "B.Mask" "B.Paste")
			(net "GND")
		)
		(pad "242" smd rect
			(at -4.59994 87.54999 270)
			(size 1.8034 0.508)
			(layers "B.Cu" "B.Mask" "B.Paste")
			(net "M_F_DQ<33>")
		)
		(pad "243" smd rect
			(at -4.59994 88.399874 270)
			(size 1.8034 0.508)
			(layers "B.Cu" "B.Mask" "B.Paste")
			(net "GND")
		)
		(pad "244" smd rect
			(at -4.59994 89.250012 270)
			(size 1.8034 0.508)
			(layers "B.Cu" "B.Mask" "B.Paste")
			(net "M_F_DQS_DN<4>")
		)
		(pad "245" smd rect
			(at -4.59994 90.099896 270)
			(size 1.8034 0.508)
			(layers "B.Cu" "B.Mask" "B.Paste")
			(net "M_F_DQS_DP<4>")
		)
		(pad "246" smd rect
			(at -4.59994 90.950034 270)
			(size 1.8034 0.508)
			(layers "B.Cu" "B.Mask" "B.Paste")
			(net "GND")
		)
		(pad "247" smd rect
			(at -4.59994 91.799918 270)
			(size 1.8034 0.508)
			(layers "B.Cu" "B.Mask" "B.Paste")
			(net "M_F_DQ<39>")
		)
		(pad "248" smd rect
			(at -4.59994 92.650056 270)
			(size 1.8034 0.508)
			(layers "B.Cu" "B.Mask" "B.Paste")
			(net "GND")
		)
		(pad "249" smd rect
			(at -4.59994 93.49994 270)
			(size 1.8034 0.508)
			(layers "B.Cu" "B.Mask" "B.Paste")
			(net "M_F_DQ<35>")
		)
		(pad "250" smd rect
			(at -4.59994 94.350078 270)
			(size 1.8034 0.508)
			(layers "B.Cu" "B.Mask" "B.Paste")
			(net "GND")
		)
		(pad "251" smd rect
			(at -4.59994 95.199962 270)
			(size 1.8034 0.508)
			(layers "B.Cu" "B.Mask" "B.Paste")
			(net "M_F_DQ<45>")
		)
		(pad "252" smd rect
			(at -4.59994 96.0501 270)
			(size 1.8034 0.508)
			(layers "B.Cu" "B.Mask" "B.Paste")
			(net "GND")
		)
		(pad "253" smd rect
			(at -4.59994 96.899984 270)
			(size 1.8034 0.508)
			(layers "B.Cu" "B.Mask" "B.Paste")
			(net "M_F_DQ<41>")
		)
		(pad "254" smd rect
			(at -4.59994 97.750122 270)
			(size 1.8034 0.508)
			(layers "B.Cu" "B.Mask" "B.Paste")
			(net "GND")
		)
		(pad "255" smd rect
			(at -4.59994 98.600006 270)
			(size 1.8034 0.508)
			(layers "B.Cu" "B.Mask" "B.Paste")
			(net "M_F_DQS_DN<5>")
		)
		(pad "256" smd rect
			(at -4.59994 99.44989 270)
			(size 1.8034 0.508)
			(layers "B.Cu" "B.Mask" "B.Paste")
			(net "M_F_DQS_DP<5>")
		)
		(pad "257" smd rect
			(at -4.59994 100.300028 270)
			(size 1.8034 0.508)
			(layers "B.Cu" "B.Mask" "B.Paste")
			(net "GND")
		)
		(pad "258" smd rect
			(at -4.59994 101.149912 270)
			(size 1.8034 0.508)
			(layers "B.Cu" "B.Mask" "B.Paste")
			(net "M_F_DQ<47>")
		)
		(pad "259" smd rect
			(at -4.59994 102.00005 270)
			(size 1.8034 0.508)
			(layers "B.Cu" "B.Mask" "B.Paste")
			(net "GND")
		)
		(pad "260" smd rect
			(at -4.59994 102.849934 270)
			(size 1.8034 0.508)
			(layers "B.Cu" "B.Mask" "B.Paste")
			(net "M_F_DQ<43>")
		)
		(pad "261" smd rect
			(at -4.59994 103.700072 270)
			(size 1.8034 0.508)
			(layers "B.Cu" "B.Mask" "B.Paste")
			(net "GND")
		)
		(pad "262" smd rect
			(at -4.59994 104.549956 270)
			(size 1.8034 0.508)
			(layers "B.Cu" "B.Mask" "B.Paste")
			(net "M_F_DQ<53>")
		)
		(pad "263" smd rect
			(at -4.59994 105.400094 270)
			(size 1.8034 0.508)
			(layers "B.Cu" "B.Mask" "B.Paste")
			(net "GND")
		)
		(pad "264" smd rect
			(at -4.59994 106.249978 270)
			(size 1.8034 0.508)
			(layers "B.Cu" "B.Mask" "B.Paste")
			(net "M_F_DQ<49>")
		)
		(pad "265" smd rect
			(at -4.59994 107.100116 270)
			(size 1.8034 0.508)
			(layers "B.Cu" "B.Mask" "B.Paste")
			(net "GND")
		)
		(pad "266" smd rect
			(at -4.59994 107.95 270)
			(size 1.8034 0.508)
			(layers "B.Cu" "B.Mask" "B.Paste")
			(net "M_F_DQS_DN<6>")
		)
		(pad "267" smd rect
			(at -4.59994 108.799884 270)
			(size 1.8034 0.508)
			(layers "B.Cu" "B.Mask" "B.Paste")
			(net "M_F_DQS_DP<6>")
		)
		(pad "268" smd rect
			(at -4.59994 109.650022 270)
			(size 1.8034 0.508)
			(layers "B.Cu" "B.Mask" "B.Paste")
			(net "GND")
		)
		(pad "269" smd rect
			(at -4.59994 110.499906 270)
			(size 1.8034 0.508)
			(layers "B.Cu" "B.Mask" "B.Paste")
			(net "M_F_DQ<55>")
		)
		(pad "270" smd rect
			(at -4.59994 111.350044 270)
			(size 1.8034 0.508)
			(layers "B.Cu" "B.Mask" "B.Paste")
			(net "GND")
		)
		(pad "271" smd rect
			(at -4.59994 112.199928 270)
			(size 1.8034 0.508)
			(layers "B.Cu" "B.Mask" "B.Paste")
			(net "M_F_DQ<51>")
		)
		(pad "272" smd rect
			(at -4.59994 113.050066 270)
			(size 1.8034 0.508)
			(layers "B.Cu" "B.Mask" "B.Paste")
			(net "GND")
		)
		(pad "273" smd rect
			(at -4.59994 113.89995 270)
			(size 1.8034 0.508)
			(layers "B.Cu" "B.Mask" "B.Paste")
			(net "M_F_DQ<61>")
		)
		(pad "274" smd rect
			(at -4.59994 114.750088 270)
			(size 1.8034 0.508)
			(layers "B.Cu" "B.Mask" "B.Paste")
			(net "GND")
		)
		(pad "275" smd rect
			(at -4.59994 115.599972 270)
			(size 1.8034 0.508)
			(layers "B.Cu" "B.Mask" "B.Paste")
			(net "M_F_DQ<57>")
		)
		(pad "276" smd rect
			(at -4.59994 116.45011 270)
			(size 1.8034 0.508)
			(layers "B.Cu" "B.Mask" "B.Paste")
			(net "GND")
		)
		(pad "277" smd rect
			(at -4.59994 117.299994 270)
			(size 1.8034 0.508)
			(layers "B.Cu" "B.Mask" "B.Paste")
			(net "M_F_DQS_DN<7>")
		)
		(pad "278" smd rect
			(at -4.59994 118.149878 270)
			(size 1.8034 0.508)
			(layers "B.Cu" "B.Mask" "B.Paste")
			(net "M_F_DQS_DP<7>")
		)
		(pad "279" smd rect
			(at -4.59994 119.000016 270)
			(size 1.8034 0.508)
			(layers "B.Cu" "B.Mask" "B.Paste")
			(net "GND")
		)
		(pad "280" smd rect
			(at -4.59994 119.8499 270)
			(size 1.8034 0.508)
			(layers "B.Cu" "B.Mask" "B.Paste")
			(net "M_F_DQ<63>")
		)
		(pad "281" smd rect
			(at -4.59994 120.700038 270)
			(size 1.8034 0.508)
			(layers "B.Cu" "B.Mask" "B.Paste")
			(net "GND")
		)
		(pad "282" smd rect
			(at -4.59994 121.549922 270)
			(size 1.8034 0.508)
			(layers "B.Cu" "B.Mask" "B.Paste")
			(net "M_F_DQ<59>")
		)
		(pad "283" smd rect
			(at -4.59994 122.40006 270)
			(size 1.8034 0.508)
			(layers "B.Cu" "B.Mask" "B.Paste")
			(net "GND")
		)
		(pad "284" smd rect
			(at -4.59994 123.249944 270)
			(size 1.8034 0.508)
			(layers "B.Cu" "B.Mask" "B.Paste")
			(net "PVPP_DEF")
		)
		(pad "285" smd rect
			(at -4.59994 124.100082 270)
			(size 1.8034 0.508)
			(layers "B.Cu" "B.Mask" "B.Paste")
			(net "SMB_DDR_DEF_VPP_SDA")
		)
		(pad "286" smd rect
			(at -4.59994 124.949966 270)
			(size 1.8034 0.508)
			(layers "B.Cu" "B.Mask" "B.Paste")
			(net "PVPP_DEF")
		)
		(pad "287" smd rect
			(at -4.59994 125.800104 270)
			(size 1.8034 0.508)
			(layers "B.Cu" "B.Mask" "B.Paste")
			(net "PVPP_DEF")
		)
		(pad "288" smd rect
			(at -4.59994 126.649988 270)
			(size 1.8034 0.508)
			(layers "B.Cu" "B.Mask" "B.Paste")
			(net "PVPP_DEF")
		)
	)
)
